(kicad_pcb
	(version 20260206)
	(generator "pcbnew")
	(generator_version "10.0")
	(general
		(thickness 1.6)
		(legacy_teardrops no)
	)
	(paper "A4")
	(title_block
		(title "01162023_DA0F0TEBIF0_F0T_Expander_BD_F_brd_V02_OCP.brd")
		(comment 1 "Grand Teton / footprints 5134-5140 of 9728")
	)
	(layers
		(0 "F.Cu" signal "TOP")
		(4 "In1.Cu" signal "GND")
		(6 "In2.Cu" signal "VCC")
		(8 "In3.Cu" signal "VCC1")
		(10 "In4.Cu" signal "GND1")
		(12 "In5.Cu" signal "IN1")
		(14 "In6.Cu" signal "GND2")
		(16 "In7.Cu" signal "IN2")
		(18 "In8.Cu" signal "GND3")
		(20 "In9.Cu" signal "IN3")
		(22 "In10.Cu" signal "GND4")
		(24 "In11.Cu" signal "IN4")
		(26 "In12.Cu" signal "GND5")
		(28 "In13.Cu" signal "IN5")
		(30 "In14.Cu" signal "GND6")
		(32 "In15.Cu" signal "IN6")
		(34 "In16.Cu" signal "GND7")
		(2 "B.Cu" signal "BOTTOM")
		(9 "F.Adhes" user "F.Adhesive")
		(11 "B.Adhes" user "B.Adhesive")
		(13 "F.Paste" user "Package Geometry/Pastemask Top")
		(15 "B.Paste" user "Package Geometry/Pastemask Bottom")
		(5 "F.SilkS" user "Ref Des/Silkscreen Top")
		(7 "B.SilkS" user "Ref Des/Silkscreen Bottom")
		(1 "F.Mask" user "Board Geometry/Soldermask Top")
		(3 "B.Mask" user "Board Geometry/Soldermask Bottom")
		(17 "Dwgs.User" user "User.Drawings")
		(19 "Cmts.User" user "User.Comments")
		(21 "Eco1.User" user "User.Eco1")
		(23 "Eco2.User" user "User.Eco2")
		(25 "Edge.Cuts" user "Board Geometry/Outline")
		(27 "Margin" user)
		(31 "F.CrtYd" user "Package Geometry/Place Bound Top")
		(29 "B.CrtYd" user "Package Geometry/Place Bound Bottom")
		(35 "F.Fab" user "Ref Des/Assembly Top")
		(33 "B.Fab" user "Ref Des/Assembly Bottom")
	)
	(footprint ""
		(layer "F.Cu")
		(at 360.032808 -162.003994 90)
		(property "Reference" "PC834"
			(at 0 0 90)
			(layer "F.SilkS")
			(hide yes)
			(effects
				(font
					(size 1.27 1.27)
				)
			)
		)
		(property "Value" ""
			(at 0 0 90)
			(layer "F.Fab")
			(effects
				(font
					(size 1.27 1.27)
				)
			)
		)
		(duplicate_pad_numbers_are_jumpers no)
		(fp_line
			(start 0.7874 -0.4064)
			(end 0.7874 0.4064)
			(stroke
				(width 0.1524)
				(type default)
			)
			(layer "F.SilkS")
		)
		(fp_line
			(start -0.7874 -0.4064)
			(end 0.7874 -0.4064)
			(stroke
				(width 0.1524)
				(type default)
			)
			(layer "F.SilkS")
		)
		(fp_line
			(start 0.7874 0.4064)
			(end -0.7874 0.4064)
			(stroke
				(width 0.1524)
				(type default)
			)
			(layer "F.SilkS")
		)
		(fp_line
			(start -0.7874 0.4064)
			(end -0.7874 -0.4064)
			(stroke
				(width 0.1524)
				(type default)
			)
			(layer "F.SilkS")
		)
		(fp_line
			(start -0.12065 -0.305054)
			(end -0.12065 -0.2794)
			(stroke
				(width 0.1)
				(type default)
			)
			(layer "F.Fab")
		)
		(fp_line
			(start -0.67945 -0.305054)
			(end -0.12065 -0.305054)
			(stroke
				(width 0.1)
				(type default)
			)
			(layer "F.Fab")
		)
		(fp_line
			(start 0.67945 -0.3048)
			(end 0.67945 0.3048)
			(stroke
				(width 0.1)
				(type default)
			)
			(layer "F.Fab")
		)
		(fp_line
			(start 0.12065 -0.3048)
			(end 0.67945 -0.3048)
			(stroke
				(width 0.1)
				(type default)
			)
			(layer "F.Fab")
		)
		(fp_line
			(start 0.12065 -0.2794)
			(end 0.12065 -0.3048)
			(stroke
				(width 0.1)
				(type default)
			)
			(layer "F.Fab")
		)
		(fp_line
			(start -0.12065 -0.2794)
			(end 0.12065 -0.2794)
			(stroke
				(width 0.1)
				(type default)
			)
			(layer "F.Fab")
		)
		(fp_line
			(start 0.120396 0.2794)
			(end -0.12065 0.2794)
			(stroke
				(width 0.1)
				(type default)
			)
			(layer "F.Fab")
		)
		(fp_line
			(start -0.12065 0.2794)
			(end -0.12065 0.3048)
			(stroke
				(width 0.1)
				(type default)
			)
			(layer "F.Fab")
		)
		(fp_line
			(start 0.67945 0.3048)
			(end 0.120396 0.3048)
			(stroke
				(width 0.1)
				(type default)
			)
			(layer "F.Fab")
		)
		(fp_line
			(start 0.120396 0.3048)
			(end 0.120396 0.2794)
			(stroke
				(width 0.1)
				(type default)
			)
			(layer "F.Fab")
		)
		(fp_line
			(start -0.12065 0.3048)
			(end -0.67945 0.3048)
			(stroke
				(width 0.1)
				(type default)
			)
			(layer "F.Fab")
		)
		(fp_line
			(start -0.67945 0.3048)
			(end -0.67945 -0.305054)
			(stroke
				(width 0.1)
				(type default)
			)
			(layer "F.Fab")
		)
		(pad "1" smd circle
			(at -0.40005 0 90)
			(size 0 0)
			(layers "F.Cu" "F.Mask" "F.Paste")
			(net "P12V_NIC6_CO_ISET_R")
		)
		(pad "2" smd circle
			(at 0.40005 0 90)
			(size 0 0)
			(layers "F.Cu" "F.Mask" "F.Paste")
			(net "GND")
		)
	)
	(footprint ""
		(layer "F.Cu")
		(at 221.990158 -83.659472)
		(property "Reference" "R5768"
			(at 0 0 0)
			(layer "F.SilkS")
			(hide yes)
			(effects
				(font
					(size 1.27 1.27)
				)
			)
		)
		(property "Value" ""
			(at 0 0 0)
			(layer "F.Fab")
			(effects
				(font
					(size 1.27 1.27)
				)
			)
		)
		(duplicate_pad_numbers_are_jumpers no)
		(fp_line
			(start -0.7874 -0.4064)
			(end 0.7874 -0.4064)
			(stroke
				(width 0.1524)
				(type default)
			)
			(layer "F.SilkS")
		)
		(fp_line
			(start -0.7874 0.4064)
			(end -0.7874 -0.4064)
			(stroke
				(width 0.1524)
				(type default)
			)
			(layer "F.SilkS")
		)
		(fp_line
			(start 0.7874 -0.4064)
			(end 0.7874 0.4064)
			(stroke
				(width 0.1524)
				(type default)
			)
			(layer "F.SilkS")
		)
		(fp_line
			(start 0.7874 0.4064)
			(end -0.7874 0.4064)
			(stroke
				(width 0.1524)
				(type default)
			)
			(layer "F.SilkS")
		)
		(fp_line
			(start -0.67945 -0.305054)
			(end -0.12065 -0.305054)
			(stroke
				(width 0.1)
				(type default)
			)
			(layer "F.Fab")
		)
		(fp_line
			(start -0.67945 0.3048)
			(end -0.67945 -0.305054)
			(stroke
				(width 0.1)
				(type default)
			)
			(layer "F.Fab")
		)
		(fp_line
			(start -0.12065 -0.305054)
			(end -0.12065 -0.2794)
			(stroke
				(width 0.1)
				(type default)
			)
			(layer "F.Fab")
		)
		(fp_line
			(start -0.12065 -0.2794)
			(end 0.12065 -0.2794)
			(stroke
				(width 0.1)
				(type default)
			)
			(layer "F.Fab")
		)
		(fp_line
			(start -0.12065 0.2794)
			(end -0.12065 0.3048)
			(stroke
				(width 0.1)
				(type default)
			)
			(layer "F.Fab")
		)
		(fp_line
			(start -0.12065 0.3048)
			(end -0.67945 0.3048)
			(stroke
				(width 0.1)
				(type default)
			)
			(layer "F.Fab")
		)
		(fp_line
			(start 0.120396 0.2794)
			(end -0.12065 0.2794)
			(stroke
				(width 0.1)
				(type default)
			)
			(layer "F.Fab")
		)
		(fp_line
			(start 0.120396 0.3048)
			(end 0.120396 0.2794)
			(stroke
				(width 0.1)
				(type default)
			)
			(layer "F.Fab")
		)
		(fp_line
			(start 0.12065 -0.3048)
			(end 0.67945 -0.3048)
			(stroke
				(width 0.1)
				(type default)
			)
			(layer "F.Fab")
		)
		(fp_line
			(start 0.12065 -0.2794)
			(end 0.12065 -0.3048)
			(stroke
				(width 0.1)
				(type default)
			)
			(layer "F.Fab")
		)
		(fp_line
			(start 0.67945 -0.3048)
			(end 0.67945 0.3048)
			(stroke
				(width 0.1)
				(type default)
			)
			(layer "F.Fab")
		)
		(fp_line
			(start 0.67945 0.3048)
			(end 0.120396 0.3048)
			(stroke
				(width 0.1)
				(type default)
			)
			(layer "F.Fab")
		)
		(pad "1" smd circle
			(at -0.40005 0)
			(size 0 0)
			(layers "F.Cu" "F.Mask" "F.Paste")
			(net "SSD14_LED")
		)
		(pad "2" smd circle
			(at 0.40005 0)
			(size 0 0)
			(layers "F.Cu" "F.Mask" "F.Paste")
			(net "SSD14_LED_R")
		)
	)
	(footprint ""
		(layer "F.Cu")
		(at 460.340964 -524.207486 180)
		(property "Reference" "HANDLE_0"
			(at -3.6322 -1.402334 0)
			(unlocked yes)
			(layer "B.SilkS")
			(effects
				(font
					(size 0.7874 0.5842)
					(thickness 0.1524)
				)
				(justify mirror)
			)
		)
		(property "Value" ""
			(at 0 0 180)
			(layer "F.Fab")
			(effects
				(font
					(size 1.27 1.27)
				)
			)
		)
		(duplicate_pad_numbers_are_jumpers no)
		(pad "1" thru_hole circle
			(at 0 0 180)
			(size 0.4572 0.4572)
			(drill 0.2032)
			(layers "*.Cu" "*.Mask")
			(remove_unused_layers no)
			(net "Net_9178")
			(clearance 0.127)
			(thermal_gap 0.127)
			(padstack
				(mode front_inner_back)
				(layer "Inner"
					(shape circle)
					(size 0.4572 0.4572)
					(clearance 0.127)
				)
				(layer "B.Cu"
					(shape circle)
					(size 0.508 0.508)
					(clearance 0.1016)
				)
			)
		)
	)
	(footprint ""
		(layer "F.Cu")
		(at 152.345898 -261.663434)
		(property "Reference" "C3213"
			(at 0 0 0)
			(layer "F.SilkS")
			(hide yes)
			(effects
				(font
					(size 1.27 1.27)
				)
			)
		)
		(property "Value" ""
			(at 0 0 0)
			(layer "F.Fab")
			(effects
				(font
					(size 1.27 1.27)
				)
			)
		)
		(duplicate_pad_numbers_are_jumpers no)
		(fp_line
			(start -1.2954 -0.5842)
			(end 1.2954 -0.5842)
			(stroke
				(width 0.1524)
				(type default)
			)
			(layer "F.SilkS")
		)
		(fp_line
			(start -1.2954 0.5842)
			(end -1.2954 -0.5842)
			(stroke
				(width 0.1524)
				(type default)
			)
			(layer "F.SilkS")
		)
		(fp_line
			(start 1.2954 -0.5842)
			(end 1.2954 0.5842)
			(stroke
				(width 0.1524)
				(type default)
			)
			(layer "F.SilkS")
		)
		(fp_line
			(start 1.2954 0.5842)
			(end -1.2954 0.5842)
			(stroke
				(width 0.1524)
				(type default)
			)
			(layer "F.SilkS")
		)
		(fp_line
			(start -1.1938 -0.4064)
			(end -0.8636 -0.4064)
			(stroke
				(width 0.1)
				(type default)
			)
			(layer "F.Fab")
		)
		(fp_line
			(start -1.1938 0.4064)
			(end -1.1938 -0.4064)
			(stroke
				(width 0.1)
				(type default)
			)
			(layer "F.Fab")
		)
		(fp_line
			(start -0.8636 -0.4572)
			(end 0.8636 -0.4572)
			(stroke
				(width 0.1)
				(type default)
			)
			(layer "F.Fab")
		)
		(fp_line
			(start -0.8636 -0.4064)
			(end -0.8636 -0.4572)
			(stroke
				(width 0.1)
				(type default)
			)
			(layer "F.Fab")
		)
		(fp_line
			(start -0.8636 0.4064)
			(end -1.1938 0.4064)
			(stroke
				(width 0.1)
				(type default)
			)
			(layer "F.Fab")
		)
		(fp_line
			(start -0.8636 0.4572)
			(end -0.8636 0.4064)
			(stroke
				(width 0.1)
				(type default)
			)
			(layer "F.Fab")
		)
		(fp_line
			(start 0.8636 -0.4572)
			(end 0.8636 -0.4064)
			(stroke
				(width 0.1)
				(type default)
			)
			(layer "F.Fab")
		)
		(fp_line
			(start 0.8636 -0.4064)
			(end 1.1938 -0.4064)
			(stroke
				(width 0.1)
				(type default)
			)
			(layer "F.Fab")
		)
		(fp_line
			(start 0.8636 0.4064)
			(end 0.8636 0.4572)
			(stroke
				(width 0.1)
				(type default)
			)
			(layer "F.Fab")
		)
		(fp_line
			(start 0.8636 0.4572)
			(end -0.8636 0.4572)
			(stroke
				(width 0.1)
				(type default)
			)
			(layer "F.Fab")
		)
		(fp_line
			(start 1.1938 -0.4064)
			(end 1.1938 0.4064)
			(stroke
				(width 0.1)
				(type default)
			)
			(layer "F.Fab")
		)
		(fp_line
			(start 1.1938 0.4064)
			(end 0.8636 0.4064)
			(stroke
				(width 0.1)
				(type default)
			)
			(layer "F.Fab")
		)
		(pad "1" smd rect
			(at -0.7366 0 270)
			(size 0.7112 0.8128)
			(layers "F.Cu" "F.Mask" "F.Paste")
			(net "PCEPLL3_VDDA18_PEX1")
		)
		(pad "2" smd rect
			(at 0.7366 0 270)
			(size 0.7112 0.8128)
			(layers "F.Cu" "F.Mask" "F.Paste")
			(net "GND")
		)
	)
	(footprint ""
		(layer "F.Cu")
		(at 177.892456 -158.080202 90)
		(property "Reference" "R3306"
			(at 0 0 90)
			(layer "F.SilkS")
			(hide yes)
			(effects
				(font
					(size 1.27 1.27)
				)
			)
		)
		(property "Value" ""
			(at 0 0 90)
			(layer "F.Fab")
			(effects
				(font
					(size 1.27 1.27)
				)
			)
		)
		(duplicate_pad_numbers_are_jumpers no)
		(fp_line
			(start 0.7874 -0.4064)
			(end 0.7874 0.4064)
			(stroke
				(width 0.1524)
				(type default)
			)
			(layer "F.SilkS")
		)
		(fp_line
			(start -0.7874 -0.4064)
			(end 0.7874 -0.4064)
			(stroke
				(width 0.1524)
				(type default)
			)
			(layer "F.SilkS")
		)
		(fp_line
			(start 0.7874 0.4064)
			(end -0.7874 0.4064)
			(stroke
				(width 0.1524)
				(type default)
			)
			(layer "F.SilkS")
		)
		(fp_line
			(start -0.7874 0.4064)
			(end -0.7874 -0.4064)
			(stroke
				(width 0.1524)
				(type default)
			)
			(layer "F.SilkS")
		)
		(fp_line
			(start -0.12065 -0.305054)
			(end -0.12065 -0.2794)
			(stroke
				(width 0.1)
				(type default)
			)
			(layer "F.Fab")
		)
		(fp_line
			(start -0.67945 -0.305054)
			(end -0.12065 -0.305054)
			(stroke
				(width 0.1)
				(type default)
			)
			(layer "F.Fab")
		)
		(fp_line
			(start 0.67945 -0.3048)
			(end 0.67945 0.3048)
			(stroke
				(width 0.1)
				(type default)
			)
			(layer "F.Fab")
		)
		(fp_line
			(start 0.12065 -0.3048)
			(end 0.67945 -0.3048)
			(stroke
				(width 0.1)
				(type default)
			)
			(layer "F.Fab")
		)
		(fp_line
			(start 0.12065 -0.2794)
			(end 0.12065 -0.3048)
			(stroke
				(width 0.1)
				(type default)
			)
			(layer "F.Fab")
		)
		(fp_line
			(start -0.12065 -0.2794)
			(end 0.12065 -0.2794)
			(stroke
				(width 0.1)
				(type default)
			)
			(layer "F.Fab")
		)
		(fp_line
			(start 0.120396 0.2794)
			(end -0.12065 0.2794)
			(stroke
				(width 0.1)
				(type default)
			)
			(layer "F.Fab")
		)
		(fp_line
			(start -0.12065 0.2794)
			(end -0.12065 0.3048)
			(stroke
				(width 0.1)
				(type default)
			)
			(layer "F.Fab")
		)
		(fp_line
			(start 0.67945 0.3048)
			(end 0.120396 0.3048)
			(stroke
				(width 0.1)
				(type default)
			)
			(layer "F.Fab")
		)
		(fp_line
			(start 0.120396 0.3048)
			(end 0.120396 0.2794)
			(stroke
				(width 0.1)
				(type default)
			)
			(layer "F.Fab")
		)
		(fp_line
			(start -0.12065 0.3048)
			(end -0.67945 0.3048)
			(stroke
				(width 0.1)
				(type default)
			)
			(layer "F.Fab")
		)
		(fp_line
			(start -0.67945 0.3048)
			(end -0.67945 -0.305054)
			(stroke
				(width 0.1)
				(type default)
			)
			(layer "F.Fab")
		)
		(pad "1" smd circle
			(at -0.40005 0 90)
			(size 0 0)
			(layers "F.Cu" "F.Mask" "F.Paste")
			(net "FM_SYS_THROTTLE_R")
		)
		(pad "2" smd circle
			(at 0.40005 0 90)
			(size 0 0)
			(layers "F.Cu" "F.Mask" "F.Paste")
			(net "FM_SYS_THROTTLE_NIC2")
		)
	)
	(footprint ""
		(layer "F.Cu")
		(at 465.58073 -524.540988 180)
		(property "Reference" "SCREW_SSD1_2"
			(at -5.207 -1.402334 0)
			(unlocked yes)
			(layer "B.SilkS")
			(effects
				(font
					(size 0.7874 0.5842)
					(thickness 0.1524)
				)
				(justify mirror)
			)
		)
		(property "Value" ""
			(at 0 0 180)
			(layer "F.Fab")
			(effects
				(font
					(size 1.27 1.27)
				)
			)
		)
		(duplicate_pad_numbers_are_jumpers no)
		(pad "1" thru_hole circle
			(at 0 0 180)
			(size 0.4572 0.4572)
			(drill 0.2032)
			(layers "*.Cu" "*.Mask")
			(remove_unused_layers no)
			(net "Net_9141")
			(clearance 0.127)
			(thermal_gap 0.127)
			(padstack
				(mode front_inner_back)
				(layer "Inner"
					(shape circle)
					(size 0.4572 0.4572)
					(clearance 0.127)
				)
				(layer "B.Cu"
					(shape circle)
					(size 0.508 0.508)
					(clearance 0.1016)
				)
			)
		)
	)
	(footprint ""
		(layer "F.Cu")
		(at 329.726544 -55.418228 90)
		(property "Reference" "PC440"
			(at 0 0 90)
			(layer "F.SilkS")
			(hide yes)
			(effects
				(font
					(size 1.27 1.27)
				)
			)
		)
		(property "Value" ""
			(at 0 0 90)
			(layer "F.Fab")
			(effects
				(font
					(size 1.27 1.27)
				)
			)
		)
		(duplicate_pad_numbers_are_jumpers no)
		(fp_line
			(start 0.7874 -0.4064)
			(end 0.7874 0.4064)
			(stroke
				(width 0.1524)
				(type default)
			)
			(layer "F.SilkS")
		)
		(fp_line
			(start -0.7874 -0.4064)
			(end 0.7874 -0.4064)
			(stroke
				(width 0.1524)
				(type default)
			)
			(layer "F.SilkS")
		)
		(fp_line
			(start 0.7874 0.4064)
			(end -0.7874 0.4064)
			(stroke
				(width 0.1524)
				(type default)
			)
			(layer "F.SilkS")
		)
		(fp_line
			(start -0.7874 0.4064)
			(end -0.7874 -0.4064)
			(stroke
				(width 0.1524)
				(type default)
			)
			(layer "F.SilkS")
		)
		(fp_line
			(start -0.12065 -0.305054)
			(end -0.12065 -0.2794)
			(stroke
				(width 0.1)
				(type default)
			)
			(layer "F.Fab")
		)
		(fp_line
			(start -0.67945 -0.305054)
			(end -0.12065 -0.305054)
			(stroke
				(width 0.1)
				(type default)
			)
			(layer "F.Fab")
		)
		(fp_line
			(start 0.67945 -0.3048)
			(end 0.67945 0.3048)
			(stroke
				(width 0.1)
				(type default)
			)
			(layer "F.Fab")
		)
		(fp_line
			(start 0.12065 -0.3048)
			(end 0.67945 -0.3048)
			(stroke
				(width 0.1)
				(type default)
			)
			(layer "F.Fab")
		)
		(fp_line
			(start 0.12065 -0.2794)
			(end 0.12065 -0.3048)
			(stroke
				(width 0.1)
				(type default)
			)
			(layer "F.Fab")
		)
		(fp_line
			(start -0.12065 -0.2794)
			(end 0.12065 -0.2794)
			(stroke
				(width 0.1)
				(type default)
			)
			(layer "F.Fab")
		)
		(fp_line
			(start 0.120396 0.2794)
			(end -0.12065 0.2794)
			(stroke
				(width 0.1)
				(type default)
			)
			(layer "F.Fab")
		)
		(fp_line
			(start -0.12065 0.2794)
			(end -0.12065 0.3048)
			(stroke
				(width 0.1)
				(type default)
			)
			(layer "F.Fab")
		)
		(fp_line
			(start 0.67945 0.3048)
			(end 0.120396 0.3048)
			(stroke
				(width 0.1)
				(type default)
			)
			(layer "F.Fab")
		)
		(fp_line
			(start 0.120396 0.3048)
			(end 0.120396 0.2794)
			(stroke
				(width 0.1)
				(type default)
			)
			(layer "F.Fab")
		)
		(fp_line
			(start -0.12065 0.3048)
			(end -0.67945 0.3048)
			(stroke
				(width 0.1)
				(type default)
			)
			(layer "F.Fab")
		)
		(fp_line
			(start -0.67945 0.3048)
			(end -0.67945 -0.305054)
			(stroke
				(width 0.1)
				(type default)
			)
			(layer "F.Fab")
		)
		(pad "1" smd circle
			(at -0.40005 0 90)
			(size 0 0)
			(layers "F.Cu" "F.Mask" "F.Paste")
			(net "P12V_SSD11_R")
		)
		(pad "2" smd circle
			(at 0.40005 0 90)
			(size 0 0)
			(layers "F.Cu" "F.Mask" "F.Paste")
			(net "GND")
		)
	)
)
